# T6G (Grand Teton) — schematic netlist excerpt (pin names and nets, part order shuffled) for the footprints in the layout excerpt that follows; sources: Cadence DE-HDL packaged netlist, KiCad conversion of 04192023_DAF0TMB3IC0_F0TG_MB_C_brd_V02_OCP.brd

U5201  TUSB211IRWBR  EMPTY  pkg X2QFN12_0-4_1-6X1-6  page 234
  D1M  = USB2_HUB_BUF_SWB_R_DN
  D1P  = USB2_HUB_BUF_SWB_R_DP
  TEST  = TP_USB2_TEST
  CD  = TP_USB2_CD
  RSTN  = PD_U5201_RSTN
  EQ  = PD_U5201_EQ
  D2P  = USB2_HUB_BUF_SWB_R_DP
  D2M  = USB2_HUB_BUF_SWB_R_DN
  ENA_HS  = TP_USB2_ENA_HS
  GND  = GND
  VREG  = PD_U5201_VREG
  VCC  = P3V3_AUX

R705  Q_RES  0 5% EMPTY  pkg 0603LF  page 334 : A = P0V9_CPU1_RT_2D ; B = P0V9_CPU1_RT1_2A_2D

(kicad_pcb
	(version 20260206)
	(generator "pcbnew")
	(generator_version "10.0")
	(general
		(thickness 1.6)
		(legacy_teardrops no)
	)
	(paper "A4")
	(title_block
		(title "04192023_DAF0TMB3IC0_F0TG_MB_C_brd_V02_OCP.brd")
		(comment 1 "Grand Teton / footprints 5129-5130 of 8354")
	)
	(layers
		(0 "F.Cu" signal "TOP")
		(4 "In1.Cu" signal "GND")
		(6 "In2.Cu" signal "IN1")
		(8 "In3.Cu" signal "GND1")
		(10 "In4.Cu" signal "IN2")
		(12 "In5.Cu" signal "GND2")
		(14 "In6.Cu" signal "IN3")
		(16 "In7.Cu" signal "GND3")
		(18 "In8.Cu" signal "VCC")
		(20 "In9.Cu" signal "VCC1")
		(22 "In10.Cu" signal "GND4")
		(24 "In11.Cu" signal "IN4")
		(26 "In12.Cu" signal "GND5")
		(28 "In13.Cu" signal "IN5")
		(30 "In14.Cu" signal "GND6")
		(32 "In15.Cu" signal "IN6")
		(34 "In16.Cu" signal "GND7")
		(2 "B.Cu" signal "BOTTOM")
		(9 "F.Adhes" user "F.Adhesive")
		(11 "B.Adhes" user "B.Adhesive")
		(13 "F.Paste" user "Package Geometry/Pastemask Top")
		(15 "B.Paste" user "Package Geometry/Pastemask Bottom")
		(5 "F.SilkS" user "Ref Des/Silkscreen Top")
		(7 "B.SilkS" user "Ref Des/Silkscreen Bottom")
		(1 "F.Mask" user "Board Geometry/Soldermask Top")
		(3 "B.Mask" user "Board Geometry/Soldermask Bottom")
		(17 "Dwgs.User" user "User.Drawings")
		(19 "Cmts.User" user "User.Comments")
		(21 "Eco1.User" user "User.Eco1")
		(23 "Eco2.User" user "User.Eco2")
		(25 "Edge.Cuts" user "Board Geometry/Outline")
		(27 "Margin" user)
		(31 "F.CrtYd" user "Package Geometry/Place Bound Top")
		(29 "B.CrtYd" user "Package Geometry/Place Bound Bottom")
		(35 "F.Fab" user "Ref Des/Assembly Top")
		(33 "B.Fab" user "Ref Des/Assembly Bottom")
	)
	(footprint ""
		(layer "B.Cu")
		(at 72.416416 -393.242546 180)
		(property "Reference" "R705"
			(at 0 0 0)
			(layer "B.SilkS")
			(hide yes)
			(effects
				(font
					(size 1.27 1.27)
				)
				(justify mirror)
			)
		)
		(property "Value" ""
			(at 0 0 0)
			(layer "B.Fab")
			(effects
				(font
					(size 1.27 1.27)
				)
				(justify mirror)
			)
		)
		(duplicate_pad_numbers_are_jumpers no)
		(fp_line
			(start 1.2954 0.5842)
			(end 1.2954 -0.5842)
			(stroke
				(width 0.1524)
				(type default)
			)
			(layer "B.SilkS")
		)
		(fp_line
			(start 1.2954 -0.5842)
			(end -1.2954 -0.5842)
			(stroke
				(width 0.1524)
				(type default)
			)
			(layer "B.SilkS")
		)
		(fp_line
			(start -1.2954 0.5842)
			(end 1.2954 0.5842)
			(stroke
				(width 0.1524)
				(type default)
			)
			(layer "B.SilkS")
		)
		(fp_line
			(start -1.2954 -0.5842)
			(end -1.2954 0.5842)
			(stroke
				(width 0.1524)
				(type default)
			)
			(layer "B.SilkS")
		)
		(fp_line
			(start 1.1938 0.4064)
			(end 1.1938 -0.406654)
			(stroke
				(width 0.1)
				(type default)
			)
			(layer "B.Fab")
		)
		(fp_line
			(start 1.1938 -0.406654)
			(end 0.8636 -0.406654)
			(stroke
				(width 0.1)
				(type default)
			)
			(layer "B.Fab")
		)
		(fp_line
			(start 0.8636 0.4572)
			(end 0.8636 0.4318)
			(stroke
				(width 0.1)
				(type default)
			)
			(layer "B.Fab")
		)
		(fp_line
			(start 0.8636 0.4318)
			(end 0.8636 0.4064)
			(stroke
				(width 0.1)
				(type default)
			)
			(layer "B.Fab")
		)
		(fp_line
			(start 0.8636 0.4064)
			(end 1.1938 0.4064)
			(stroke
				(width 0.1)
				(type default)
			)
			(layer "B.Fab")
		)
		(fp_line
			(start 0.8636 -0.406654)
			(end 0.8636 -0.4572)
			(stroke
				(width 0.1)
				(type default)
			)
			(layer "B.Fab")
		)
		(fp_line
			(start 0.8636 -0.4572)
			(end -0.8636 -0.4572)
			(stroke
				(width 0.1)
				(type default)
			)
			(layer "B.Fab")
		)
		(fp_line
			(start -0.8636 0.4572)
			(end 0.8636 0.4572)
			(stroke
				(width 0.1)
				(type default)
			)
			(layer "B.Fab")
		)
		(fp_line
			(start -0.8636 0.4064)
			(end -0.8636 0.4572)
			(stroke
				(width 0.1)
				(type default)
			)
			(layer "B.Fab")
		)
		(fp_line
			(start -0.8636 -0.406654)
			(end -1.1938 -0.406654)
			(stroke
				(width 0.1)
				(type default)
			)
			(layer "B.Fab")
		)
		(fp_line
			(start -0.8636 -0.4572)
			(end -0.8636 -0.406654)
			(stroke
				(width 0.1)
				(type default)
			)
			(layer "B.Fab")
		)
		(fp_line
			(start -1.1938 0.4064)
			(end -0.8636 0.4064)
			(stroke
				(width 0.1)
				(type default)
			)
			(layer "B.Fab")
		)
		(fp_line
			(start -1.1938 -0.406654)
			(end -1.1938 0.4064)
			(stroke
				(width 0.1)
				(type default)
			)
			(layer "B.Fab")
		)
		(pad "1" smd rect
			(at 0.7366 0 90)
			(size 0.7112 0.8128)
			(layers "B.Cu" "B.Mask" "B.Paste")
			(net "P0V9_CPU1_RT_2D")
		)
		(pad "2" smd rect
			(at -0.7366 0 90)
			(size 0.7112 0.8128)
			(layers "B.Cu" "B.Mask" "B.Paste")
			(net "P0V9_CPU1_RT1_2A_2D")
		)
	)
	(footprint ""
		(layer "B.Cu")
		(at 12.076684 -112.319308 -90)
		(property "Reference" "U5201"
			(at -3.494532 -1.880616 0)
			(unlocked yes)
			(layer "B.SilkS")
			(effects
				(font
					(size 0.7874 0.5842)
					(thickness 0.1524)
				)
				(justify left mirror)
			)
		)
		(property "Value" ""
			(at 0 0 90)
			(layer "B.Fab")
			(effects
				(font
					(size 1.27 1.27)
				)
				(justify mirror)
			)
		)
		(duplicate_pad_numbers_are_jumpers no)
		(fp_line
			(start -1.2446 1.2446)
			(end -1.2446 0.479044)
			(stroke
				(width 0.1524)
				(type default)
			)
			(layer "B.SilkS")
		)
		(fp_line
			(start 1.2446 1.2446)
			(end -1.2446 1.2446)
			(stroke
				(width 0.1524)
				(type default)
			)
			(layer "B.SilkS")
		)
		(fp_line
			(start 1.2446 0.593344)
			(end 1.2446 1.2446)
			(stroke
				(width 0.1524)
				(type default)
			)
			(layer "B.SilkS")
		)
		(fp_line
			(start -1.2446 -0.506476)
			(end -1.2446 -1.2446)
			(stroke
				(width 0.1524)
				(type default)
			)
			(layer "B.SilkS")
		)
		(fp_line
			(start -1.2446 -1.2446)
			(end 1.2446 -1.2446)
			(stroke
				(width 0.1524)
				(type default)
			)
			(layer "B.SilkS")
		)
		(fp_line
			(start 1.2446 -1.2446)
			(end 1.2446 -0.592836)
			(stroke
				(width 0.1524)
				(type default)
			)
			(layer "B.SilkS")
		)
		(fp_poly
			(pts
				(xy 2.23266 -0.702056) (xy 1.416812 -0.430022) (xy 1.688592 -1.246124)
			)
			(stroke
				(width 0)
				(type default)
			)
			(fill yes)
			(layer "B.SilkS")
		)
		(fp_line
			(start -0.824992 0.824992)
			(end -0.824992 -0.824992)
			(stroke
				(width 0.1)
				(type default)
			)
			(layer "B.Fab")
		)
		(fp_line
			(start 0.824992 0.824992)
			(end -0.824992 0.824992)
			(stroke
				(width 0.1)
				(type default)
			)
			(layer "B.Fab")
		)
		(fp_line
			(start -0.824992 -0.824992)
			(end 0.824992 -0.824992)
			(stroke
				(width 0.1)
				(type default)
			)
			(layer "B.Fab")
		)
		(fp_line
			(start 0.824992 -0.824992)
			(end 0.824992 0.824992)
			(stroke
				(width 0.1)
				(type default)
			)
			(layer "B.Fab")
		)
		(fp_poly
			(pts
				(xy 1.389634 -0.199898) (xy 2.159 0.184658) (xy 2.159 -0.584708)
			)
			(stroke
				(width 0)
				(type default)
			)
			(fill yes)
			(layer "B.Fab")
		)
		(pad "1" smd rect
			(at 0.700024 -0.199898 180)
			(size 0.1778 0.8128)
			(layers "B.Cu" "B.Mask" "B.Paste")
			(net "USB2_HUB_BUF_SWB_R_DN")
		)
		(pad "2" smd rect
			(at 0.700024 0.199898 180)
			(size 0.1778 0.8128)
			(layers "B.Cu" "B.Mask" "B.Paste")
			(net "USB2_HUB_BUF_SWB_R_DP")
		)
		(pad "3" smd rect
			(at 0.599948 0.8001 90)
			(size 0.1778 0.6096)
			(layers "B.Cu" "B.Mask" "B.Paste")
			(net "TP_USB2_TEST")
		)
		(pad "4" smd rect
			(at 0.199898 0.8001 90)
			(size 0.1778 0.6096)
			(layers "B.Cu" "B.Mask" "B.Paste")
			(net "TP_USB2_CD")
		)
		(pad "5" smd rect
			(at -0.199898 0.8001 90)
			(size 0.1778 0.6096)
			(layers "B.Cu" "B.Mask" "B.Paste")
			(net "PD_U5201_RSTN")
		)
		(pad "6" smd rect
			(at -0.599948 0.8001 90)
			(size 0.1778 0.6096)
			(layers "B.Cu" "B.Mask" "B.Paste")
			(net "PD_U5201_EQ")
		)
		(pad "7" smd rect
			(at -0.700024 0.199898 180)
			(size 0.1778 0.8128)
			(layers "B.Cu" "B.Mask" "B.Paste")
			(net "USB2_HUB_BUF_SWB_R_DP")
		)
		(pad "8" smd rect
			(at -0.700024 -0.199898 180)
			(size 0.1778 0.8128)
			(layers "B.Cu" "B.Mask" "B.Paste")
			(net "USB2_HUB_BUF_SWB_R_DN")
		)
		(pad "9" smd rect
			(at -0.599948 -0.8001 90)
			(size 0.1778 0.6096)
			(layers "B.Cu" "B.Mask" "B.Paste")
			(net "TP_USB2_ENA_HS")
		)
		(pad "10" smd rect
			(at -0.199898 -0.8001 90)
			(size 0.1778 0.6096)
			(layers "B.Cu" "B.Mask" "B.Paste")
			(net "GND")
		)
		(pad "11" smd rect
			(at 0.199898 -0.8001 90)
			(size 0.1778 0.6096)
			(layers "B.Cu" "B.Mask" "B.Paste")
			(net "PD_U5201_VREG")
		)
		(pad "12" smd rect
			(at 0.599948 -0.8001 90)
			(size 0.1778 0.6096)
			(layers "B.Cu" "B.Mask" "B.Paste")
			(net "P3V3_AUX")
		)
	)
)
